FILE_TYPE = MULTI_PHYS_TABLE;

PART 'FSA3357K8X'

{========================================================================================}
:VALUE        | PART_TYPE | MATERIAL | PART_NUMBER    = STANDARD    | LIFECYCLE     | PART_NUMBER   | JEDEC_TYPE      | DESCRIPTION                   | MANUFTR | MANUF_PN     | RD_CMPLS_LVL | CMPLS_LVL | FROM_PJ    | CLASS | DIP_SMD | DATA                 | EE_CHECK_LIST | FP_ECN | PSL | CREATOR | STATUS | CREATEDAY  ;
{========================================================================================}
 'FSA3357K8X' | 'SMLF'    | 'IC'     | 'AL003357009'(!) = 'Potential'      | 'End of Life'    | 'AL003357009' |'US8_0-5_2X2-3_EOL'| 'IC OTHER(8P)FSA3357K8X(US8)' | 'FAC'   | 'FSA3357K8X' | 'EP'         | ''        | 'S1U-OWEN' | 'IC'  | ''      | 'FAC_FSA3357K8X.pdf' | ''            | ''     | ''  | ''      | ''     | '20150622'
 'FSA3357K8X' | 'SMLF'    | 'EMPTY'  | 'AL003357009'(!) = 'Potential'      | 'End of Life'    | 'AL003357009' |'US8_0-5_2X2-3_EOL'| 'IC OTHER(8P)FSA3357K8X(US8)' | 'FAC'   | 'FSA3357K8X' | 'EP'         | ''        | 'S1U-OWEN' | 'IC'  | ''      | 'FAC_FSA3357K8X.pdf' | ''            | ''     | ''  | ''      | ''     | '20150622'

END_PART

END.

